(kicad_pcb
	(version 20260206)
	(generator "pcbnew")
	(generator_version "10.0")
	(general
		(thickness 1.6)
		(legacy_teardrops no)
	)
	(paper "A4")
	(title_block
		(title "12092022_DA0F0TMDCD0_F0T_Management_Board_D_brd_V3_OCP.brd")
		(comment 1 "Grand Teton / footprints 1123-1128 of 1440")
	)
	(layers
		(0 "F.Cu" signal "TOP")
		(4 "In1.Cu" signal "GND")
		(6 "In2.Cu" signal "IN1")
		(8 "In3.Cu" signal "GND1")
		(10 "In4.Cu" signal "IN2")
		(12 "In5.Cu" signal "VCC")
		(14 "In6.Cu" signal "VCC1")
		(16 "In7.Cu" signal "IN3")
		(18 "In8.Cu" signal "GND2")
		(20 "In9.Cu" signal "IN4")
		(22 "In10.Cu" signal "GND3")
		(2 "B.Cu" signal "BOTTOM")
		(9 "F.Adhes" user "F.Adhesive")
		(11 "B.Adhes" user "B.Adhesive")
		(13 "F.Paste" user "Package Geometry/Pastemask Top")
		(15 "B.Paste" user "Package Geometry/Pastemask Bottom")
		(5 "F.SilkS" user "Ref Des/Silkscreen Top")
		(7 "B.SilkS" user "Ref Des/Silkscreen Bottom")
		(1 "F.Mask" user "Board Geometry/Soldermask Top")
		(3 "B.Mask" user "Board Geometry/Soldermask Bottom")
		(17 "Dwgs.User" user "User.Drawings")
		(19 "Cmts.User" user "User.Comments")
		(21 "Eco1.User" user "User.Eco1")
		(23 "Eco2.User" user "User.Eco2")
		(25 "Edge.Cuts" user "Board Geometry/Outline")
		(27 "Margin" user)
		(31 "F.CrtYd" user "Package Geometry/Place Bound Top")
		(29 "B.CrtYd" user "Package Geometry/Place Bound Bottom")
		(35 "F.Fab" user "Ref Des/Assembly Top")
		(33 "B.Fab" user "Ref Des/Assembly Bottom")
	)
	(footprint ""
		(layer "B.Cu")
		(at 45.339 -96.8248 -90)
		(property "Reference" "R672"
			(at 0 0 90)
			(layer "B.SilkS")
			(hide yes)
			(effects
				(font
					(size 1.27 1.27)
				)
				(justify mirror)
			)
		)
		(property "Value" ""
			(at 0 0 90)
			(layer "B.Fab")
			(effects
				(font
					(size 1.27 1.27)
				)
				(justify mirror)
			)
		)
		(duplicate_pad_numbers_are_jumpers no)
		(fp_line
			(start -0.7874 0.4064)
			(end 0.7874 0.4064)
			(stroke
				(width 0.1524)
				(type default)
			)
			(layer "B.SilkS")
		)
		(fp_line
			(start 0.7874 0.4064)
			(end 0.7874 -0.4064)
			(stroke
				(width 0.1524)
				(type default)
			)
			(layer "B.SilkS")
		)
		(fp_line
			(start -0.7874 -0.4064)
			(end -0.7874 0.4064)
			(stroke
				(width 0.1524)
				(type default)
			)
			(layer "B.SilkS")
		)
		(fp_line
			(start 0.7874 -0.4064)
			(end -0.7874 -0.4064)
			(stroke
				(width 0.1524)
				(type default)
			)
			(layer "B.SilkS")
		)
		(fp_line
			(start -0.67945 0.3048)
			(end -0.120396 0.3048)
			(stroke
				(width 0.1)
				(type default)
			)
			(layer "B.Fab")
		)
		(fp_line
			(start -0.120396 0.3048)
			(end -0.120396 0.2794)
			(stroke
				(width 0.1)
				(type default)
			)
			(layer "B.Fab")
		)
		(fp_line
			(start 0.12065 0.3048)
			(end 0.67945 0.3048)
			(stroke
				(width 0.1)
				(type default)
			)
			(layer "B.Fab")
		)
		(fp_line
			(start 0.67945 0.3048)
			(end 0.67945 -0.305054)
			(stroke
				(width 0.1)
				(type default)
			)
			(layer "B.Fab")
		)
		(fp_line
			(start -0.120396 0.2794)
			(end 0.12065 0.2794)
			(stroke
				(width 0.1)
				(type default)
			)
			(layer "B.Fab")
		)
		(fp_line
			(start 0.12065 0.2794)
			(end 0.12065 0.3048)
			(stroke
				(width 0.1)
				(type default)
			)
			(layer "B.Fab")
		)
		(fp_line
			(start -0.12065 -0.2794)
			(end -0.12065 -0.3048)
			(stroke
				(width 0.1)
				(type default)
			)
			(layer "B.Fab")
		)
		(fp_line
			(start 0.12065 -0.2794)
			(end -0.12065 -0.2794)
			(stroke
				(width 0.1)
				(type default)
			)
			(layer "B.Fab")
		)
		(fp_line
			(start -0.67945 -0.3048)
			(end -0.67945 0.3048)
			(stroke
				(width 0.1)
				(type default)
			)
			(layer "B.Fab")
		)
		(fp_line
			(start -0.12065 -0.3048)
			(end -0.67945 -0.3048)
			(stroke
				(width 0.1)
				(type default)
			)
			(layer "B.Fab")
		)
		(fp_line
			(start 0.12065 -0.305054)
			(end 0.12065 -0.2794)
			(stroke
				(width 0.1)
				(type default)
			)
			(layer "B.Fab")
		)
		(fp_line
			(start 0.67945 -0.305054)
			(end 0.12065 -0.305054)
			(stroke
				(width 0.1)
				(type default)
			)
			(layer "B.Fab")
		)
		(pad "1" smd circle
			(at 0.40005 0 90)
			(size 0 0)
			(layers "B.Cu" "B.Mask" "B.Paste")
			(net "USB3_01_TXN_C")
		)
		(pad "2" smd circle
			(at -0.40005 0 90)
			(size 0 0)
			(layers "B.Cu" "B.Mask" "B.Paste")
			(net "USB3_FPNL_TXN")
		)
	)
	(footprint ""
		(layer "B.Cu")
		(at 74.774552 -35.01898 180)
		(property "Reference" "C55"
			(at 0 0 0)
			(layer "B.SilkS")
			(hide yes)
			(effects
				(font
					(size 1.27 1.27)
				)
				(justify mirror)
			)
		)
		(property "Value" ""
			(at 0 0 0)
			(layer "B.Fab")
			(effects
				(font
					(size 1.27 1.27)
				)
				(justify mirror)
			)
		)
		(duplicate_pad_numbers_are_jumpers no)
		(fp_line
			(start 1.2954 0.5842)
			(end 1.2954 -0.5842)
			(stroke
				(width 0.1524)
				(type default)
			)
			(layer "B.SilkS")
		)
		(fp_line
			(start 1.2954 -0.5842)
			(end -1.2954 -0.5842)
			(stroke
				(width 0.1524)
				(type default)
			)
			(layer "B.SilkS")
		)
		(fp_line
			(start 0 -0.5842)
			(end 0 0.5842)
			(stroke
				(width 0.1524)
				(type default)
			)
			(layer "B.SilkS")
		)
		(fp_line
			(start -1.2954 0.5842)
			(end 1.2954 0.5842)
			(stroke
				(width 0.1524)
				(type default)
			)
			(layer "B.SilkS")
		)
		(fp_line
			(start -1.2954 -0.5842)
			(end -1.2954 0.5842)
			(stroke
				(width 0.1524)
				(type default)
			)
			(layer "B.SilkS")
		)
		(fp_line
			(start 1.1938 0.4064)
			(end 1.1938 -0.4064)
			(stroke
				(width 0.1)
				(type default)
			)
			(layer "B.Fab")
		)
		(fp_line
			(start 1.1938 -0.4064)
			(end 0.8636 -0.4064)
			(stroke
				(width 0.1)
				(type default)
			)
			(layer "B.Fab")
		)
		(fp_line
			(start 0.8636 0.4572)
			(end 0.8636 0.4064)
			(stroke
				(width 0.1)
				(type default)
			)
			(layer "B.Fab")
		)
		(fp_line
			(start 0.8636 0.4064)
			(end 1.1938 0.4064)
			(stroke
				(width 0.1)
				(type default)
			)
			(layer "B.Fab")
		)
		(fp_line
			(start 0.8636 -0.4064)
			(end 0.8636 -0.4572)
			(stroke
				(width 0.1)
				(type default)
			)
			(layer "B.Fab")
		)
		(fp_line
			(start 0.8636 -0.4572)
			(end -0.8636 -0.4572)
			(stroke
				(width 0.1)
				(type default)
			)
			(layer "B.Fab")
		)
		(fp_line
			(start -0.8636 0.4572)
			(end 0.8636 0.4572)
			(stroke
				(width 0.1)
				(type default)
			)
			(layer "B.Fab")
		)
		(fp_line
			(start -0.8636 0.4064)
			(end -0.8636 0.4572)
			(stroke
				(width 0.1)
				(type default)
			)
			(layer "B.Fab")
		)
		(fp_line
			(start -0.8636 -0.4064)
			(end -1.1938 -0.4064)
			(stroke
				(width 0.1)
				(type default)
			)
			(layer "B.Fab")
		)
		(fp_line
			(start -0.8636 -0.4572)
			(end -0.8636 -0.4064)
			(stroke
				(width 0.1)
				(type default)
			)
			(layer "B.Fab")
		)
		(fp_line
			(start -1.1938 0.4064)
			(end -0.8636 0.4064)
			(stroke
				(width 0.1)
				(type default)
			)
			(layer "B.Fab")
		)
		(fp_line
			(start -1.1938 -0.4064)
			(end -1.1938 0.4064)
			(stroke
				(width 0.1)
				(type default)
			)
			(layer "B.Fab")
		)
		(pad "1" smd rect
			(at 0.7366 0 90)
			(size 0.7112 0.8128)
			(layers "B.Cu" "B.Mask" "B.Paste")
			(net "P1V2_AUX")
		)
		(pad "2" smd rect
			(at -0.7366 0 90)
			(size 0.7112 0.8128)
			(layers "B.Cu" "B.Mask" "B.Paste")
			(net "GND")
		)
	)
	(footprint ""
		(layer "B.Cu")
		(at 15.24 -83.693 90)
		(property "Reference" "R435"
			(at 0 0 90)
			(layer "B.SilkS")
			(hide yes)
			(effects
				(font
					(size 1.27 1.27)
				)
				(justify mirror)
			)
		)
		(property "Value" ""
			(at 0 0 90)
			(layer "B.Fab")
			(effects
				(font
					(size 1.27 1.27)
				)
				(justify mirror)
			)
		)
		(duplicate_pad_numbers_are_jumpers no)
		(fp_line
			(start 0.7874 -0.4064)
			(end -0.7874 -0.4064)
			(stroke
				(width 0.1524)
				(type default)
			)
			(layer "B.SilkS")
		)
		(fp_line
			(start -0.7874 -0.4064)
			(end -0.7874 0.4064)
			(stroke
				(width 0.1524)
				(type default)
			)
			(layer "B.SilkS")
		)
		(fp_line
			(start 0.7874 0.4064)
			(end 0.7874 -0.4064)
			(stroke
				(width 0.1524)
				(type default)
			)
			(layer "B.SilkS")
		)
		(fp_line
			(start -0.7874 0.4064)
			(end 0.7874 0.4064)
			(stroke
				(width 0.1524)
				(type default)
			)
			(layer "B.SilkS")
		)
		(fp_line
			(start 0.67945 -0.305054)
			(end 0.12065 -0.305054)
			(stroke
				(width 0.1)
				(type default)
			)
			(layer "B.Fab")
		)
		(fp_line
			(start 0.12065 -0.305054)
			(end 0.12065 -0.2794)
			(stroke
				(width 0.1)
				(type default)
			)
			(layer "B.Fab")
		)
		(fp_line
			(start -0.12065 -0.3048)
			(end -0.67945 -0.3048)
			(stroke
				(width 0.1)
				(type default)
			)
			(layer "B.Fab")
		)
		(fp_line
			(start -0.67945 -0.3048)
			(end -0.67945 0.3048)
			(stroke
				(width 0.1)
				(type default)
			)
			(layer "B.Fab")
		)
		(fp_line
			(start 0.12065 -0.2794)
			(end -0.12065 -0.2794)
			(stroke
				(width 0.1)
				(type default)
			)
			(layer "B.Fab")
		)
		(fp_line
			(start -0.12065 -0.2794)
			(end -0.12065 -0.3048)
			(stroke
				(width 0.1)
				(type default)
			)
			(layer "B.Fab")
		)
		(fp_line
			(start 0.12065 0.2794)
			(end 0.12065 0.3048)
			(stroke
				(width 0.1)
				(type default)
			)
			(layer "B.Fab")
		)
		(fp_line
			(start -0.120396 0.2794)
			(end 0.12065 0.2794)
			(stroke
				(width 0.1)
				(type default)
			)
			(layer "B.Fab")
		)
		(fp_line
			(start 0.67945 0.3048)
			(end 0.67945 -0.305054)
			(stroke
				(width 0.1)
				(type default)
			)
			(layer "B.Fab")
		)
		(fp_line
			(start 0.12065 0.3048)
			(end 0.67945 0.3048)
			(stroke
				(width 0.1)
				(type default)
			)
			(layer "B.Fab")
		)
		(fp_line
			(start -0.120396 0.3048)
			(end -0.120396 0.2794)
			(stroke
				(width 0.1)
				(type default)
			)
			(layer "B.Fab")
		)
		(fp_line
			(start -0.67945 0.3048)
			(end -0.120396 0.3048)
			(stroke
				(width 0.1)
				(type default)
			)
			(layer "B.Fab")
		)
		(pad "1" smd circle
			(at 0.40005 0 270)
			(size 0 0)
			(layers "B.Cu" "B.Mask" "B.Paste")
			(net "SGPIO_PLD_DO_0")
		)
		(pad "2" smd circle
			(at -0.40005 0 270)
			(size 0 0)
			(layers "B.Cu" "B.Mask" "B.Paste")
			(net "SGPIO_DO_0")
		)
	)
	(footprint ""
		(layer "B.Cu")
		(at 55.336948 -70.418198 90)
		(property "Reference" "R780"
			(at 0 0 90)
			(layer "B.SilkS")
			(hide yes)
			(effects
				(font
					(size 1.27 1.27)
				)
				(justify mirror)
			)
		)
		(property "Value" ""
			(at 0 0 90)
			(layer "B.Fab")
			(effects
				(font
					(size 1.27 1.27)
				)
				(justify mirror)
			)
		)
		(duplicate_pad_numbers_are_jumpers no)
		(fp_line
			(start 0.7874 -0.4064)
			(end -0.7874 -0.4064)
			(stroke
				(width 0.1524)
				(type default)
			)
			(layer "B.SilkS")
		)
		(fp_line
			(start -0.7874 -0.4064)
			(end -0.7874 0.4064)
			(stroke
				(width 0.1524)
				(type default)
			)
			(layer "B.SilkS")
		)
		(fp_line
			(start 0.7874 0.4064)
			(end 0.7874 -0.4064)
			(stroke
				(width 0.1524)
				(type default)
			)
			(layer "B.SilkS")
		)
		(fp_line
			(start -0.7874 0.4064)
			(end 0.7874 0.4064)
			(stroke
				(width 0.1524)
				(type default)
			)
			(layer "B.SilkS")
		)
		(fp_line
			(start 0.67945 -0.305054)
			(end 0.12065 -0.305054)
			(stroke
				(width 0.1)
				(type default)
			)
			(layer "B.Fab")
		)
		(fp_line
			(start 0.12065 -0.305054)
			(end 0.12065 -0.2794)
			(stroke
				(width 0.1)
				(type default)
			)
			(layer "B.Fab")
		)
		(fp_line
			(start -0.12065 -0.3048)
			(end -0.67945 -0.3048)
			(stroke
				(width 0.1)
				(type default)
			)
			(layer "B.Fab")
		)
		(fp_line
			(start -0.67945 -0.3048)
			(end -0.67945 0.3048)
			(stroke
				(width 0.1)
				(type default)
			)
			(layer "B.Fab")
		)
		(fp_line
			(start 0.12065 -0.2794)
			(end -0.12065 -0.2794)
			(stroke
				(width 0.1)
				(type default)
			)
			(layer "B.Fab")
		)
		(fp_line
			(start -0.12065 -0.2794)
			(end -0.12065 -0.3048)
			(stroke
				(width 0.1)
				(type default)
			)
			(layer "B.Fab")
		)
		(fp_line
			(start 0.12065 0.2794)
			(end 0.12065 0.3048)
			(stroke
				(width 0.1)
				(type default)
			)
			(layer "B.Fab")
		)
		(fp_line
			(start -0.120396 0.2794)
			(end 0.12065 0.2794)
			(stroke
				(width 0.1)
				(type default)
			)
			(layer "B.Fab")
		)
		(fp_line
			(start 0.67945 0.3048)
			(end 0.67945 -0.305054)
			(stroke
				(width 0.1)
				(type default)
			)
			(layer "B.Fab")
		)
		(fp_line
			(start 0.12065 0.3048)
			(end 0.67945 0.3048)
			(stroke
				(width 0.1)
				(type default)
			)
			(layer "B.Fab")
		)
		(fp_line
			(start -0.120396 0.3048)
			(end -0.120396 0.2794)
			(stroke
				(width 0.1)
				(type default)
			)
			(layer "B.Fab")
		)
		(fp_line
			(start -0.67945 0.3048)
			(end -0.120396 0.3048)
			(stroke
				(width 0.1)
				(type default)
			)
			(layer "B.Fab")
		)
		(pad "1" smd circle
			(at 0.40005 0 270)
			(size 0 0)
			(layers "B.Cu" "B.Mask" "B.Paste")
			(net "P2V5_AUX")
		)
		(pad "2" smd circle
			(at -0.40005 0 270)
			(size 0 0)
			(layers "B.Cu" "B.Mask" "B.Paste")
			(net "ADCVREFEXT0")
		)
	)
	(footprint ""
		(layer "B.Cu")
		(at 18.259552 -89.98712 180)
		(property "Reference" "C247"
			(at 0 0 0)
			(layer "B.SilkS")
			(hide yes)
			(effects
				(font
					(size 1.27 1.27)
				)
				(justify mirror)
			)
		)
		(property "Value" ""
			(at 0 0 0)
			(layer "B.Fab")
			(effects
				(font
					(size 1.27 1.27)
				)
				(justify mirror)
			)
		)
		(duplicate_pad_numbers_are_jumpers no)
		(fp_line
			(start 0.69215 0.2921)
			(end 0.69215 -0.2921)
			(stroke
				(width 0.1524)
				(type default)
			)
			(layer "B.SilkS")
		)
		(fp_line
			(start 0.69215 -0.2921)
			(end -0.69215 -0.2921)
			(stroke
				(width 0.1524)
				(type default)
			)
			(layer "B.SilkS")
		)
		(fp_line
			(start -0.69215 0.2921)
			(end 0.69215 0.2921)
			(stroke
				(width 0.1524)
				(type default)
			)
			(layer "B.SilkS")
		)
		(fp_line
			(start -0.69215 -0.2921)
			(end -0.69215 0.2921)
			(stroke
				(width 0.1524)
				(type default)
			)
			(layer "B.SilkS")
		)
		(fp_line
			(start 0.51435 0.2794)
			(end 0.51435 -0.2794)
			(stroke
				(width 0.1)
				(type default)
			)
			(layer "B.Fab")
		)
		(fp_line
			(start 0.51435 -0.2794)
			(end -0.51435 -0.2794)
			(stroke
				(width 0.1)
				(type default)
			)
			(layer "B.Fab")
		)
		(fp_line
			(start -0.51435 0.2794)
			(end 0.51435 0.2794)
			(stroke
				(width 0.1)
				(type default)
			)
			(layer "B.Fab")
		)
		(fp_line
			(start -0.51435 -0.2794)
			(end -0.51435 0.2794)
			(stroke
				(width 0.1)
				(type default)
			)
			(layer "B.Fab")
		)
		(pad "1" smd circle
			(at 0.40005 0)
			(size 0 0)
			(layers "B.Cu" "B.Mask" "B.Paste")
			(net "VCCIO0")
		)
		(pad "2" smd circle
			(at -0.40005 0)
			(size 0 0)
			(layers "B.Cu" "B.Mask" "B.Paste")
			(net "GND")
		)
		(zone
			(layer "B.Cu")
			(hatch none 0.5)
			(connect_pads
				(clearance 0)
			)
			(min_thickness 0.25)
			(keepout
				(tracks not_allowed)
				(vias allowed)
				(pads allowed)
				(copperpour not_allowed)
				(footprints allowed)
			)
			(placement
				(enabled no)
				(sheetname "")
			)
			(fill
				(thermal_gap 0.5)
				(thermal_bridge_width 0.5)
				(island_removal_mode 0)
			)
			(polygon
				(pts
					(xy 18.069052 -90.07475) (xy 18.160492 -90.132916) (xy 18.359882 -90.132916) (xy 18.450052 -90.07475)
					(xy 18.450052 -89.89949) (xy 18.359882 -89.84107) (xy 18.160492 -89.84107) (xy 18.069052 -89.899236)
				)
			)
		)
	)
	(footprint ""
		(layer "B.Cu")
		(at 81.129886 -44.038012 180)
		(property "Reference" "R5"
			(at 0 0 0)
			(layer "B.SilkS")
			(hide yes)
			(effects
				(font
					(size 1.27 1.27)
				)
				(justify mirror)
			)
		)
		(property "Value" ""
			(at 0 0 0)
			(layer "B.Fab")
			(effects
				(font
					(size 1.27 1.27)
				)
				(justify mirror)
			)
		)
		(duplicate_pad_numbers_are_jumpers no)
		(fp_line
			(start 0.7874 0.4064)
			(end 0.7874 -0.4064)
			(stroke
				(width 0.1524)
				(type default)
			)
			(layer "B.SilkS")
		)
		(fp_line
			(start 0.7874 -0.4064)
			(end -0.7874 -0.4064)
			(stroke
				(width 0.1524)
				(type default)
			)
			(layer "B.SilkS")
		)
		(fp_line
			(start -0.7874 0.4064)
			(end 0.7874 0.4064)
			(stroke
				(width 0.1524)
				(type default)
			)
			(layer "B.SilkS")
		)
		(fp_line
			(start -0.7874 -0.4064)
			(end -0.7874 0.4064)
			(stroke
				(width 0.1524)
				(type default)
			)
			(layer "B.SilkS")
		)
		(fp_line
			(start 0.67945 0.3048)
			(end 0.67945 -0.305054)
			(stroke
				(width 0.1)
				(type default)
			)
			(layer "B.Fab")
		)
		(fp_line
			(start 0.67945 -0.305054)
			(end 0.12065 -0.305054)
			(stroke
				(width 0.1)
				(type default)
			)
			(layer "B.Fab")
		)
		(fp_line
			(start 0.12065 0.3048)
			(end 0.67945 0.3048)
			(stroke
				(width 0.1)
				(type default)
			)
			(layer "B.Fab")
		)
		(fp_line
			(start 0.12065 0.2794)
			(end 0.12065 0.3048)
			(stroke
				(width 0.1)
				(type default)
			)
			(layer "B.Fab")
		)
		(fp_line
			(start 0.12065 -0.2794)
			(end -0.12065 -0.2794)
			(stroke
				(width 0.1)
				(type default)
			)
			(layer "B.Fab")
		)
		(fp_line
			(start 0.12065 -0.305054)
			(end 0.12065 -0.2794)
			(stroke
				(width 0.1)
				(type default)
			)
			(layer "B.Fab")
		)
		(fp_line
			(start -0.120396 0.3048)
			(end -0.120396 0.2794)
			(stroke
				(width 0.1)
				(type default)
			)
			(layer "B.Fab")
		)
		(fp_line
			(start -0.120396 0.2794)
			(end 0.12065 0.2794)
			(stroke
				(width 0.1)
				(type default)
			)
			(layer "B.Fab")
		)
		(fp_line
			(start -0.12065 -0.2794)
			(end -0.12065 -0.3048)
			(stroke
				(width 0.1)
				(type default)
			)
			(layer "B.Fab")
		)
		(fp_line
			(start -0.12065 -0.3048)
			(end -0.67945 -0.3048)
			(stroke
				(width 0.1)
				(type default)
			)
			(layer "B.Fab")
		)
		(fp_line
			(start -0.67945 0.3048)
			(end -0.120396 0.3048)
			(stroke
				(width 0.1)
				(type default)
			)
			(layer "B.Fab")
		)
		(fp_line
			(start -0.67945 -0.3048)
			(end -0.67945 0.3048)
			(stroke
				(width 0.1)
				(type default)
			)
			(layer "B.Fab")
		)
		(pad "1" smd circle
			(at 0.40005 0)
			(size 0 0)
			(layers "B.Cu" "B.Mask" "B.Paste")
			(net "PD_M_BMC_DDR4_TEN")
		)
		(pad "2" smd circle
			(at -0.40005 0)
			(size 0 0)
			(layers "B.Cu" "B.Mask" "B.Paste")
			(net "GND")
		)
	)
)
